(kicad_pcb
	(version 20260206)
	(generator "pcbnew")
	(generator_version "10.0")
	(general
		(thickness 1.6)
		(legacy_teardrops no)
	)
	(paper "A4")
	(title_block
		(title "03242023_DA0F0TMBIJ0_F0T_Motherboard_J_brd_V01_OCP.brd")
		(comment 1 "Grand Teton / footprints 262-266 of 6105")
	)
	(layers
		(0 "F.Cu" signal "TOP")
		(4 "In1.Cu" signal "GND")
		(6 "In2.Cu" signal "IN1")
		(8 "In3.Cu" signal "GND1")
		(10 "In4.Cu" signal "IN2")
		(12 "In5.Cu" signal "GND2")
		(14 "In6.Cu" signal "IN3")
		(16 "In7.Cu" signal "GND3")
		(18 "In8.Cu" signal "VCC")
		(20 "In9.Cu" signal "VCC1")
		(22 "In10.Cu" signal "GND4")
		(24 "In11.Cu" signal "IN4")
		(26 "In12.Cu" signal "GND5")
		(28 "In13.Cu" signal "IN5")
		(30 "In14.Cu" signal "GND6")
		(32 "In15.Cu" signal "IN6")
		(34 "In16.Cu" signal "GND7")
		(2 "B.Cu" signal "BOTTOM")
		(9 "F.Adhes" user "F.Adhesive")
		(11 "B.Adhes" user "B.Adhesive")
		(13 "F.Paste" user "Package Geometry/Pastemask Top")
		(15 "B.Paste" user "Package Geometry/Pastemask Bottom")
		(5 "F.SilkS" user "Ref Des/Silkscreen Top")
		(7 "B.SilkS" user "Ref Des/Silkscreen Bottom")
		(1 "F.Mask" user "Board Geometry/Soldermask Top")
		(3 "B.Mask" user "Board Geometry/Soldermask Bottom")
		(17 "Dwgs.User" user "User.Drawings")
		(19 "Cmts.User" user "User.Comments")
		(21 "Eco1.User" user "User.Eco1")
		(23 "Eco2.User" user "User.Eco2")
		(25 "Edge.Cuts" user "Board Geometry/Outline")
		(27 "Margin" user)
		(31 "F.CrtYd" user "Package Geometry/Place Bound Top")
		(29 "B.CrtYd" user "Package Geometry/Place Bound Bottom")
		(35 "F.Fab" user "Ref Des/Assembly Top")
		(33 "B.Fab" user "Ref Des/Assembly Bottom")
	)
	(footprint ""
		(layer "F.Cu")
		(at 99.724464 -65.141094 -90)
		(property "Reference" "R3091"
			(at 0 0 270)
			(layer "F.SilkS")
			(hide yes)
			(effects
				(font
					(size 1.27 1.27)
				)
			)
		)
		(property "Value" ""
			(at 0 0 270)
			(layer "F.Fab")
			(effects
				(font
					(size 1.27 1.27)
				)
			)
		)
		(duplicate_pad_numbers_are_jumpers no)
		(fp_line
			(start -0.7874 0.4064)
			(end -0.7874 -0.4064)
			(stroke
				(width 0.1524)
				(type default)
			)
			(layer "F.SilkS")
		)
		(fp_line
			(start 0.7874 0.4064)
			(end -0.7874 0.4064)
			(stroke
				(width 0.1524)
				(type default)
			)
			(layer "F.SilkS")
		)
		(fp_line
			(start -0.7874 -0.4064)
			(end 0.7874 -0.4064)
			(stroke
				(width 0.1524)
				(type default)
			)
			(layer "F.SilkS")
		)
		(fp_line
			(start 0.7874 -0.4064)
			(end 0.7874 0.4064)
			(stroke
				(width 0.1524)
				(type default)
			)
			(layer "F.SilkS")
		)
		(fp_line
			(start -0.67945 0.3048)
			(end -0.67945 -0.305054)
			(stroke
				(width 0.1)
				(type default)
			)
			(layer "F.Fab")
		)
		(fp_line
			(start -0.12065 0.3048)
			(end -0.67945 0.3048)
			(stroke
				(width 0.1)
				(type default)
			)
			(layer "F.Fab")
		)
		(fp_line
			(start 0.120396 0.3048)
			(end 0.120396 0.2794)
			(stroke
				(width 0.1)
				(type default)
			)
			(layer "F.Fab")
		)
		(fp_line
			(start 0.67945 0.3048)
			(end 0.120396 0.3048)
			(stroke
				(width 0.1)
				(type default)
			)
			(layer "F.Fab")
		)
		(fp_line
			(start -0.12065 0.2794)
			(end -0.12065 0.3048)
			(stroke
				(width 0.1)
				(type default)
			)
			(layer "F.Fab")
		)
		(fp_line
			(start 0.120396 0.2794)
			(end -0.12065 0.2794)
			(stroke
				(width 0.1)
				(type default)
			)
			(layer "F.Fab")
		)
		(fp_line
			(start -0.12065 -0.2794)
			(end 0.12065 -0.2794)
			(stroke
				(width 0.1)
				(type default)
			)
			(layer "F.Fab")
		)
		(fp_line
			(start 0.12065 -0.2794)
			(end 0.12065 -0.3048)
			(stroke
				(width 0.1)
				(type default)
			)
			(layer "F.Fab")
		)
		(fp_line
			(start 0.12065 -0.3048)
			(end 0.67945 -0.3048)
			(stroke
				(width 0.1)
				(type default)
			)
			(layer "F.Fab")
		)
		(fp_line
			(start 0.67945 -0.3048)
			(end 0.67945 0.3048)
			(stroke
				(width 0.1)
				(type default)
			)
			(layer "F.Fab")
		)
		(fp_line
			(start -0.67945 -0.305054)
			(end -0.12065 -0.305054)
			(stroke
				(width 0.1)
				(type default)
			)
			(layer "F.Fab")
		)
		(fp_line
			(start -0.12065 -0.305054)
			(end -0.12065 -0.2794)
			(stroke
				(width 0.1)
				(type default)
			)
			(layer "F.Fab")
		)
		(pad "1" smd circle
			(at -0.40005 0 270)
			(size 0 0)
			(layers "F.Cu" "F.Mask" "F.Paste")
			(net "LED_PWRGD_PVCCIN_CPU0")
		)
		(pad "2" smd circle
			(at 0.40005 0 270)
			(size 0 0)
			(layers "F.Cu" "F.Mask" "F.Paste")
			(net "P3V3_AUX")
		)
	)
	(footprint ""
		(layer "F.Cu")
		(at 337.536282 -341.729822 90)
		(property "Reference" "PR1770"
			(at 0 0 90)
			(layer "F.SilkS")
			(hide yes)
			(effects
				(font
					(size 1.27 1.27)
				)
			)
		)
		(property "Value" ""
			(at 0 0 90)
			(layer "F.Fab")
			(effects
				(font
					(size 1.27 1.27)
				)
			)
		)
		(duplicate_pad_numbers_are_jumpers no)
		(fp_line
			(start 0.7874 -0.4064)
			(end 0.7874 0.4064)
			(stroke
				(width 0.1524)
				(type default)
			)
			(layer "F.SilkS")
		)
		(fp_line
			(start -0.7874 -0.4064)
			(end 0.7874 -0.4064)
			(stroke
				(width 0.1524)
				(type default)
			)
			(layer "F.SilkS")
		)
		(fp_line
			(start 0.7874 0.4064)
			(end -0.7874 0.4064)
			(stroke
				(width 0.1524)
				(type default)
			)
			(layer "F.SilkS")
		)
		(fp_line
			(start -0.7874 0.4064)
			(end -0.7874 -0.4064)
			(stroke
				(width 0.1524)
				(type default)
			)
			(layer "F.SilkS")
		)
		(fp_line
			(start -0.12065 -0.305054)
			(end -0.12065 -0.2794)
			(stroke
				(width 0.1)
				(type default)
			)
			(layer "F.Fab")
		)
		(fp_line
			(start -0.67945 -0.305054)
			(end -0.12065 -0.305054)
			(stroke
				(width 0.1)
				(type default)
			)
			(layer "F.Fab")
		)
		(fp_line
			(start 0.67945 -0.3048)
			(end 0.67945 0.3048)
			(stroke
				(width 0.1)
				(type default)
			)
			(layer "F.Fab")
		)
		(fp_line
			(start 0.12065 -0.3048)
			(end 0.67945 -0.3048)
			(stroke
				(width 0.1)
				(type default)
			)
			(layer "F.Fab")
		)
		(fp_line
			(start 0.12065 -0.2794)
			(end 0.12065 -0.3048)
			(stroke
				(width 0.1)
				(type default)
			)
			(layer "F.Fab")
		)
		(fp_line
			(start -0.12065 -0.2794)
			(end 0.12065 -0.2794)
			(stroke
				(width 0.1)
				(type default)
			)
			(layer "F.Fab")
		)
		(fp_line
			(start 0.120396 0.2794)
			(end -0.12065 0.2794)
			(stroke
				(width 0.1)
				(type default)
			)
			(layer "F.Fab")
		)
		(fp_line
			(start -0.12065 0.2794)
			(end -0.12065 0.3048)
			(stroke
				(width 0.1)
				(type default)
			)
			(layer "F.Fab")
		)
		(fp_line
			(start 0.67945 0.3048)
			(end 0.120396 0.3048)
			(stroke
				(width 0.1)
				(type default)
			)
			(layer "F.Fab")
		)
		(fp_line
			(start 0.120396 0.3048)
			(end 0.120396 0.2794)
			(stroke
				(width 0.1)
				(type default)
			)
			(layer "F.Fab")
		)
		(fp_line
			(start -0.12065 0.3048)
			(end -0.67945 0.3048)
			(stroke
				(width 0.1)
				(type default)
			)
			(layer "F.Fab")
		)
		(fp_line
			(start -0.67945 0.3048)
			(end -0.67945 -0.305054)
			(stroke
				(width 0.1)
				(type default)
			)
			(layer "F.Fab")
		)
		(pad "1" smd circle
			(at -0.40005 0 90)
			(size 0 0)
			(layers "F.Cu" "F.Mask" "F.Paste")
			(net "SW_PVCCIN_CPU0_BOOT6")
		)
		(pad "2" smd circle
			(at 0.40005 0 90)
			(size 0 0)
			(layers "F.Cu" "F.Mask" "F.Paste")
			(net "SW_PVCCIN_CPU0_BOOT6_R")
		)
	)
	(footprint ""
		(layer "F.Cu")
		(at 99.067366 -338.180172 -90)
		(property "Reference" "PC565"
			(at 0 0 270)
			(layer "F.SilkS")
			(hide yes)
			(effects
				(font
					(size 1.27 1.27)
				)
			)
		)
		(property "Value" ""
			(at 0 0 270)
			(layer "F.Fab")
			(effects
				(font
					(size 1.27 1.27)
				)
			)
		)
		(duplicate_pad_numbers_are_jumpers no)
		(fp_line
			(start -0.7874 0.4064)
			(end -0.7874 -0.4064)
			(stroke
				(width 0.1524)
				(type default)
			)
			(layer "F.SilkS")
		)
		(fp_line
			(start 0.7874 0.4064)
			(end -0.7874 0.4064)
			(stroke
				(width 0.1524)
				(type default)
			)
			(layer "F.SilkS")
		)
		(fp_line
			(start -0.7874 -0.4064)
			(end 0.7874 -0.4064)
			(stroke
				(width 0.1524)
				(type default)
			)
			(layer "F.SilkS")
		)
		(fp_line
			(start 0.7874 -0.4064)
			(end 0.7874 0.4064)
			(stroke
				(width 0.1524)
				(type default)
			)
			(layer "F.SilkS")
		)
		(fp_line
			(start -0.67945 0.3048)
			(end -0.67945 -0.305054)
			(stroke
				(width 0.1)
				(type default)
			)
			(layer "F.Fab")
		)
		(fp_line
			(start -0.12065 0.3048)
			(end -0.67945 0.3048)
			(stroke
				(width 0.1)
				(type default)
			)
			(layer "F.Fab")
		)
		(fp_line
			(start 0.120396 0.3048)
			(end 0.120396 0.2794)
			(stroke
				(width 0.1)
				(type default)
			)
			(layer "F.Fab")
		)
		(fp_line
			(start 0.67945 0.3048)
			(end 0.120396 0.3048)
			(stroke
				(width 0.1)
				(type default)
			)
			(layer "F.Fab")
		)
		(fp_line
			(start -0.12065 0.2794)
			(end -0.12065 0.3048)
			(stroke
				(width 0.1)
				(type default)
			)
			(layer "F.Fab")
		)
		(fp_line
			(start 0.120396 0.2794)
			(end -0.12065 0.2794)
			(stroke
				(width 0.1)
				(type default)
			)
			(layer "F.Fab")
		)
		(fp_line
			(start -0.12065 -0.2794)
			(end 0.12065 -0.2794)
			(stroke
				(width 0.1)
				(type default)
			)
			(layer "F.Fab")
		)
		(fp_line
			(start 0.12065 -0.2794)
			(end 0.12065 -0.3048)
			(stroke
				(width 0.1)
				(type default)
			)
			(layer "F.Fab")
		)
		(fp_line
			(start 0.12065 -0.3048)
			(end 0.67945 -0.3048)
			(stroke
				(width 0.1)
				(type default)
			)
			(layer "F.Fab")
		)
		(fp_line
			(start 0.67945 -0.3048)
			(end 0.67945 0.3048)
			(stroke
				(width 0.1)
				(type default)
			)
			(layer "F.Fab")
		)
		(fp_line
			(start -0.67945 -0.305054)
			(end -0.12065 -0.305054)
			(stroke
				(width 0.1)
				(type default)
			)
			(layer "F.Fab")
		)
		(fp_line
			(start -0.12065 -0.305054)
			(end -0.12065 -0.2794)
			(stroke
				(width 0.1)
				(type default)
			)
			(layer "F.Fab")
		)
		(pad "1" smd circle
			(at -0.40005 0 270)
			(size 0 0)
			(layers "F.Cu" "F.Mask" "F.Paste")
			(net "SW_PVCCIN_CPU1_BOOT1_R")
		)
		(pad "2" smd circle
			(at 0.40005 0 270)
			(size 0 0)
			(layers "F.Cu" "F.Mask" "F.Paste")
			(net "SW_PVCCIN_CPU1_BOOTR1")
		)
	)
	(footprint ""
		(layer "F.Cu")
		(at 367.762282 -58.533792)
		(property "Reference" "U17"
			(at -2.032 -3.27533 0)
			(unlocked yes)
			(layer "F.SilkS")
			(effects
				(font
					(size 0.7874 0.5842)
					(thickness 0.1524)
				)
				(justify left)
			)
		)
		(property "Value" ""
			(at 0 0 0)
			(layer "F.Fab")
			(effects
				(font
					(size 1.27 1.27)
				)
			)
		)
		(duplicate_pad_numbers_are_jumpers no)
		(fp_line
			(start -2.0066 -2.5527)
			(end -0.5715 -2.5527)
			(stroke
				(width 0.1524)
				(type default)
			)
			(layer "F.SilkS")
		)
		(fp_line
			(start -2.0066 2.5527)
			(end -2.0066 -2.5527)
			(stroke
				(width 0.1524)
				(type default)
			)
			(layer "F.SilkS")
		)
		(fp_line
			(start -0.5715 -2.5527)
			(end 0 -1.9812)
			(stroke
				(width 0.1524)
				(type default)
			)
			(layer "F.SilkS")
		)
		(fp_line
			(start 0 -1.9812)
			(end 0.5715 -2.5527)
			(stroke
				(width 0.1524)
				(type default)
			)
			(layer "F.SilkS")
		)
		(fp_line
			(start 0.5715 -2.5527)
			(end 2.0066 -2.5527)
			(stroke
				(width 0.1524)
				(type default)
			)
			(layer "F.SilkS")
		)
		(fp_line
			(start 2.0066 -2.5527)
			(end 2.0066 2.5527)
			(stroke
				(width 0.1524)
				(type default)
			)
			(layer "F.SilkS")
		)
		(fp_line
			(start 2.0066 2.5527)
			(end -2.0066 2.5527)
			(stroke
				(width 0.1524)
				(type default)
			)
			(layer "F.SilkS")
		)
		(fp_poly
			(pts
				(xy -4.36372 -2.233168) (xy -3.81 -1.905) (xy -4.36372 -1.608328)
			)
			(stroke
				(width 0)
				(type default)
			)
			(fill yes)
			(layer "F.SilkS")
		)
		(fp_line
			(start -2.249932 -2.549906)
			(end 2.249932 -2.549906)
			(stroke
				(width 0.1)
				(type default)
			)
			(layer "F.Fab")
		)
		(fp_line
			(start -2.249932 2.549906)
			(end -2.249932 -2.549906)
			(stroke
				(width 0.1)
				(type default)
			)
			(layer "F.Fab")
		)
		(fp_line
			(start 2.249932 -2.549906)
			(end 2.249932 2.549906)
			(stroke
				(width 0.1)
				(type default)
			)
			(layer "F.Fab")
		)
		(fp_line
			(start 2.249932 2.549906)
			(end -2.249932 2.549906)
			(stroke
				(width 0.1)
				(type default)
			)
			(layer "F.Fab")
		)
		(fp_poly
			(pts
				(xy -4.36372 -1.608328) (xy -4.36372 -2.233168) (xy -3.81 -1.905)
			)
			(stroke
				(width 0)
				(type default)
			)
			(fill yes)
			(layer "F.Fab")
		)
		(pad "1" smd rect
			(at -2.921 -1.949958 270)
			(size 0.3556 1.4986)
			(layers "F.Cu" "F.Mask" "F.Paste")
			(net "PWRGD_PVNN_MAIN_CPU0")
		)
		(pad "2" smd rect
			(at -2.921 -1.299972 270)
			(size 0.3556 1.4986)
			(layers "F.Cu" "F.Mask" "F.Paste")
			(net "JTAG_DBP_TMS")
		)
		(pad "3" smd rect
			(at -2.921 -0.649986 270)
			(size 0.3556 1.4986)
			(layers "F.Cu" "F.Mask" "F.Paste")
			(net "JTAG_DBP_CPU_QS_GTL_TMS")
		)
		(pad "4" smd rect
			(at -2.921 0 270)
			(size 0.3556 1.4986)
			(layers "F.Cu" "F.Mask" "F.Paste")
			(net "PWRGD_PVNN_MAIN_CPU0")
		)
		(pad "5" smd rect
			(at -2.921 0.649986 270)
			(size 0.3556 1.4986)
			(layers "F.Cu" "F.Mask" "F.Paste")
			(net "JTAG_DBP_TDI")
		)
		(pad "6" smd rect
			(at -2.921 1.299972 270)
			(size 0.3556 1.4986)
			(layers "F.Cu" "F.Mask" "F.Paste")
			(net "JTAG_QS_MUX_GTL_TDI")
		)
		(pad "7" smd rect
			(at -2.921 1.949958 270)
			(size 0.3556 1.4986)
			(layers "F.Cu" "F.Mask" "F.Paste")
			(net "GND")
		)
		(pad "8" smd rect
			(at 2.921 1.949958 270)
			(size 0.3556 1.4986)
			(layers "F.Cu" "F.Mask" "F.Paste")
			(net "TP_74CB_B8")
		)
		(pad "9" smd rect
			(at 2.921 1.299972 270)
			(size 0.3556 1.4986)
			(layers "F.Cu" "F.Mask" "F.Paste")
			(net "PD_74CB_A9")
		)
		(pad "10" smd rect
			(at 2.921 0.649986 270)
			(size 0.3556 1.4986)
			(layers "F.Cu" "F.Mask" "F.Paste")
			(net "PWRGD_PVNN_MAIN_CPU0")
		)
		(pad "11" smd rect
			(at 2.921 0 270)
			(size 0.3556 1.4986)
			(layers "F.Cu" "F.Mask" "F.Paste")
			(net "JTAG_MUX_QS_GTL_TDO")
		)
		(pad "12" smd rect
			(at 2.921 -0.649986 270)
			(size 0.3556 1.4986)
			(layers "F.Cu" "F.Mask" "F.Paste")
			(net "JTAG_DBP_TDO")
		)
		(pad "13" smd rect
			(at 2.921 -1.299972 270)
			(size 0.3556 1.4986)
			(layers "F.Cu" "F.Mask" "F.Paste")
			(net "PWRGD_PVNN_MAIN_CPU0")
		)
		(pad "14" smd rect
			(at 2.921 -1.949958 270)
			(size 0.3556 1.4986)
			(layers "F.Cu" "F.Mask" "F.Paste")
			(net "P3V3_AUX")
		)
	)
	(footprint ""
		(layer "F.Cu")
		(at 432.916838 -180.97627)
		(property "Reference" "PU81"
			(at 3.54838 7.799832 0)
			(unlocked yes)
			(layer "F.SilkS")
			(effects
				(font
					(size 0.7874 0.5842)
					(thickness 0.1524)
				)
				(justify left)
			)
		)
		(property "Value" ""
			(at 0 0 0)
			(layer "F.Fab")
			(effects
				(font
					(size 1.27 1.27)
				)
			)
		)
		(duplicate_pad_numbers_are_jumpers no)
		(fp_line
			(start -1.050036 -1.549908)
			(end -0.503936 -1.549908)
			(stroke
				(width 0.1524)
				(type default)
			)
			(layer "F.SilkS")
		)
		(fp_line
			(start -1.050036 -1.253998)
			(end -1.050036 -1.549908)
			(stroke
				(width 0.1524)
				(type default)
			)
			(layer "F.SilkS")
		)
		(fp_line
			(start -1.050036 1.549908)
			(end -1.050036 1.253998)
			(stroke
				(width 0.1524)
				(type default)
			)
			(layer "F.SilkS")
		)
		(fp_line
			(start -0.503936 1.549908)
			(end -1.050036 1.549908)
			(stroke
				(width 0.1524)
				(type default)
			)
			(layer "F.SilkS")
		)
		(fp_line
			(start 0.503936 -1.549908)
			(end 1.050036 -1.549908)
			(stroke
				(width 0.1524)
				(type default)
			)
			(layer "F.SilkS")
		)
		(fp_line
			(start 1.050036 -1.549908)
			(end 1.050036 -1.253998)
			(stroke
				(width 0.1524)
				(type default)
			)
			(layer "F.SilkS")
		)
		(fp_line
			(start 1.050036 1.253998)
			(end 1.050036 1.549908)
			(stroke
				(width 0.1524)
				(type default)
			)
			(layer "F.SilkS")
		)
		(fp_line
			(start 1.050036 1.549908)
			(end 0.503936 1.549908)
			(stroke
				(width 0.1524)
				(type default)
			)
			(layer "F.SilkS")
		)
		(fp_poly
			(pts
				(xy -1.285494 -1.491742) (xy -2.093722 -1.761236) (xy -1.554988 -2.29997)
			)
			(stroke
				(width 0)
				(type default)
			)
			(fill yes)
			(layer "F.SilkS")
		)
		(fp_line
			(start -1.050036 -1.549908)
			(end 1.050036 -1.549908)
			(stroke
				(width 0.1)
				(type default)
			)
			(layer "F.Fab")
		)
		(fp_line
			(start -1.050036 1.549908)
			(end -1.050036 -1.549908)
			(stroke
				(width 0.1)
				(type default)
			)
			(layer "F.Fab")
		)
		(fp_line
			(start 1.050036 -1.549908)
			(end 1.050036 1.549908)
			(stroke
				(width 0.1)
				(type default)
			)
			(layer "F.Fab")
		)
		(fp_line
			(start 1.050036 1.549908)
			(end -1.050036 1.549908)
			(stroke
				(width 0.1)
				(type default)
			)
			(layer "F.Fab")
		)
		(fp_poly
			(pts
				(xy -2.2352 -0.618998) (xy -2.2352 -1.380998) (xy -1.4732 -0.999998)
			)
			(stroke
				(width 0)
				(type default)
			)
			(fill yes)
			(layer "F.Fab")
		)
		(pad "1" smd circle
			(at -0.94996 -0.999998 270)
			(size 0 0)
			(layers "F.Cu" "F.Mask" "F.Paste")
			(net "GND")
		)
		(pad "2" smd rect
			(at -0.849884 -0.499872 90)
			(size 0.254 0.9144)
			(layers "F.Cu" "F.Mask" "F.Paste")
			(net "SW_PVNN_MAIN_CPU0_SW")
		)
		(pad "3" smd rect
			(at -0.649986 0 90)
			(size 0.254 1.3208)
			(layers "F.Cu" "F.Mask" "F.Paste")
			(net "SW_P12V_PVCCINFAON_CPU0_FLT")
		)
		(pad "4" smd rect
			(at -0.849884 0.499872 90)
			(size 0.254 0.9144)
			(layers "F.Cu" "F.Mask" "F.Paste")
			(net "PVNN_MAIN_CPU0_CS")
		)
		(pad "5" smd circle
			(at -0.94996 0.999998 270)
			(size 0 0)
			(layers "F.Cu" "F.Mask" "F.Paste")
			(net "FM_PVNN_MAIN_CPU0_EN")
		)
		(pad "6" smd circle
			(at -0.249936 1.450086)
			(size 0 0)
			(layers "F.Cu" "F.Mask" "F.Paste")
			(net "PVNN_MAIN_CPU0_FB")
		)
		(pad "7" smd circle
			(at 0.249936 1.450086)
			(size 0 0)
			(layers "F.Cu" "F.Mask" "F.Paste")
			(net "GND")
		)
		(pad "8" smd circle
			(at 0.94996 0.999998 90)
			(size 0 0)
			(layers "F.Cu" "F.Mask" "F.Paste")
			(net "PVNN_MAIN_CPU0_REF")
		)
		(pad "9" smd rect
			(at 0.849884 0.499872 90)
			(size 0.254 0.9144)
			(layers "F.Cu" "F.Mask" "F.Paste")
			(net "PWRGD_PVNN_MAIN_CPU0_R")
		)
		(pad "10" smd rect
			(at 0.849884 0 90)
			(size 0.254 0.9144)
			(layers "F.Cu" "F.Mask" "F.Paste")
			(net "SW_PVNN_MAIN_CPU0_BST")
		)
		(pad "11" smd rect
			(at 0.849884 -0.499872 90)
			(size 0.254 0.9144)
			(layers "F.Cu" "F.Mask" "F.Paste")
			(net "SW_PVNN_MAIN_CPU0_SW")
		)
		(pad "12" smd circle
			(at 0.94996 -0.999998 90)
			(size 0 0)
			(layers "F.Cu" "F.Mask" "F.Paste")
			(net "PVNN_MAIN_CPU0_MODE")
		)
		(pad "13" smd circle
			(at 0.249936 -1.450086 180)
			(size 0 0)
			(layers "F.Cu" "F.Mask" "F.Paste")
			(net "PVNN_MAIN_CPU0_VCC")
		)
		(pad "14" smd circle
			(at -0.249936 -1.450086 180)
			(size 0 0)
			(layers "F.Cu" "F.Mask" "F.Paste")
			(net "GND")
		)
	)
)
